# S9S_MB_2U (Grand Teton) — schematic netlist excerpt (pin names and nets, part order shuffled) for the footprints in the layout excerpt that follows; sources: Cadence DE-HDL packaged netlist, KiCad conversion of 03242023_DA0F0TMBIJ0_F0T_Motherboard_J_brd_V01_OCP.brd

R1451  Q_RES  2K 1% CHIP  pkg 0402LF  page 183 : A = PU_SMB_SML3_3V3AUX_PCH_SCL ; B = P3V3_AUX
R936  Q_RES  10K 1% CHIP  pkg 0402LF  page 128 : A = RST_CPU0_DRAM_EF_N ; B = GND

(kicad_pcb
	(version 20260206)
	(generator "pcbnew")
	(generator_version "10.0")
	(general
		(thickness 1.6)
		(legacy_teardrops no)
	)
	(paper "A4")
	(title_block
		(title "03242023_DA0F0TMBIJ0_F0T_Motherboard_J_brd_V01_OCP.brd")
		(comment 1 "Grand Teton / footprints 2972-2973 of 6105")
	)
	(layers
		(0 "F.Cu" signal "TOP")
		(4 "In1.Cu" signal "GND")
		(6 "In2.Cu" signal "IN1")
		(8 "In3.Cu" signal "GND1")
		(10 "In4.Cu" signal "IN2")
		(12 "In5.Cu" signal "GND2")
		(14 "In6.Cu" signal "IN3")
		(16 "In7.Cu" signal "GND3")
		(18 "In8.Cu" signal "VCC")
		(20 "In9.Cu" signal "VCC1")
		(22 "In10.Cu" signal "GND4")
		(24 "In11.Cu" signal "IN4")
		(26 "In12.Cu" signal "GND5")
		(28 "In13.Cu" signal "IN5")
		(30 "In14.Cu" signal "GND6")
		(32 "In15.Cu" signal "IN6")
		(34 "In16.Cu" signal "GND7")
		(2 "B.Cu" signal "BOTTOM")
		(9 "F.Adhes" user "F.Adhesive")
		(11 "B.Adhes" user "B.Adhesive")
		(13 "F.Paste" user "Package Geometry/Pastemask Top")
		(15 "B.Paste" user "Package Geometry/Pastemask Bottom")
		(5 "F.SilkS" user "Ref Des/Silkscreen Top")
		(7 "B.SilkS" user "Ref Des/Silkscreen Bottom")
		(1 "F.Mask" user "Board Geometry/Soldermask Top")
		(3 "B.Mask" user "Board Geometry/Soldermask Bottom")
		(17 "Dwgs.User" user "User.Drawings")
		(19 "Cmts.User" user "User.Comments")
		(21 "Eco1.User" user "User.Eco1")
		(23 "Eco2.User" user "User.Eco2")
		(25 "Edge.Cuts" user "Board Geometry/Outline")
		(27 "Margin" user)
		(31 "F.CrtYd" user "Package Geometry/Place Bound Top")
		(29 "B.CrtYd" user "Package Geometry/Place Bound Bottom")
		(35 "F.Fab" user "Ref Des/Assembly Top")
		(33 "B.Fab" user "Ref Des/Assembly Bottom")
	)
	(footprint ""
		(layer "F.Cu")
		(at 115.95608 -122.132598 90)
		(property "Reference" "R936"
			(at 0 0 90)
			(layer "F.SilkS")
			(hide yes)
			(effects
				(font
					(size 1.27 1.27)
				)
			)
		)
		(property "Value" ""
			(at 0 0 90)
			(layer "F.Fab")
			(effects
				(font
					(size 1.27 1.27)
				)
			)
		)
		(duplicate_pad_numbers_are_jumpers no)
		(fp_line
			(start 0.7874 -0.4064)
			(end 0.7874 0.4064)
			(stroke
				(width 0.1524)
				(type default)
			)
			(layer "F.SilkS")
		)
		(fp_line
			(start -0.7874 -0.4064)
			(end 0.7874 -0.4064)
			(stroke
				(width 0.1524)
				(type default)
			)
			(layer "F.SilkS")
		)
		(fp_line
			(start 0.7874 0.4064)
			(end -0.7874 0.4064)
			(stroke
				(width 0.1524)
				(type default)
			)
			(layer "F.SilkS")
		)
		(fp_line
			(start -0.7874 0.4064)
			(end -0.7874 -0.4064)
			(stroke
				(width 0.1524)
				(type default)
			)
			(layer "F.SilkS")
		)
		(fp_line
			(start -0.12065 -0.305054)
			(end -0.12065 -0.2794)
			(stroke
				(width 0.1)
				(type default)
			)
			(layer "F.Fab")
		)
		(fp_line
			(start -0.67945 -0.305054)
			(end -0.12065 -0.305054)
			(stroke
				(width 0.1)
				(type default)
			)
			(layer "F.Fab")
		)
		(fp_line
			(start 0.67945 -0.3048)
			(end 0.67945 0.3048)
			(stroke
				(width 0.1)
				(type default)
			)
			(layer "F.Fab")
		)
		(fp_line
			(start 0.12065 -0.3048)
			(end 0.67945 -0.3048)
			(stroke
				(width 0.1)
				(type default)
			)
			(layer "F.Fab")
		)
		(fp_line
			(start 0.12065 -0.2794)
			(end 0.12065 -0.3048)
			(stroke
				(width 0.1)
				(type default)
			)
			(layer "F.Fab")
		)
		(fp_line
			(start -0.12065 -0.2794)
			(end 0.12065 -0.2794)
			(stroke
				(width 0.1)
				(type default)
			)
			(layer "F.Fab")
		)
		(fp_line
			(start 0.120396 0.2794)
			(end -0.12065 0.2794)
			(stroke
				(width 0.1)
				(type default)
			)
			(layer "F.Fab")
		)
		(fp_line
			(start -0.12065 0.2794)
			(end -0.12065 0.3048)
			(stroke
				(width 0.1)
				(type default)
			)
			(layer "F.Fab")
		)
		(fp_line
			(start 0.67945 0.3048)
			(end 0.120396 0.3048)
			(stroke
				(width 0.1)
				(type default)
			)
			(layer "F.Fab")
		)
		(fp_line
			(start 0.120396 0.3048)
			(end 0.120396 0.2794)
			(stroke
				(width 0.1)
				(type default)
			)
			(layer "F.Fab")
		)
		(fp_line
			(start -0.12065 0.3048)
			(end -0.67945 0.3048)
			(stroke
				(width 0.1)
				(type default)
			)
			(layer "F.Fab")
		)
		(fp_line
			(start -0.67945 0.3048)
			(end -0.67945 -0.305054)
			(stroke
				(width 0.1)
				(type default)
			)
			(layer "F.Fab")
		)
		(pad "1" smd circle
			(at -0.40005 0 90)
			(size 0 0)
			(layers "F.Cu" "F.Mask" "F.Paste")
			(net "RST_CPU0_DRAM_EF_N")
		)
		(pad "2" smd circle
			(at 0.40005 0 90)
			(size 0 0)
			(layers "F.Cu" "F.Mask" "F.Paste")
			(net "GND")
		)
	)
	(footprint ""
		(layer "F.Cu")
		(at 309.522622 -40.122348 180)
		(property "Reference" "R1451"
			(at 0 0 180)
			(layer "F.SilkS")
			(hide yes)
			(effects
				(font
					(size 1.27 1.27)
				)
			)
		)
		(property "Value" ""
			(at 0 0 180)
			(layer "F.Fab")
			(effects
				(font
					(size 1.27 1.27)
				)
			)
		)
		(duplicate_pad_numbers_are_jumpers no)
		(fp_line
			(start 0.7874 0.4064)
			(end -0.7874 0.4064)
			(stroke
				(width 0.1524)
				(type default)
			)
			(layer "F.SilkS")
		)
		(fp_line
			(start 0.7874 -0.4064)
			(end 0.7874 0.4064)
			(stroke
				(width 0.1524)
				(type default)
			)
			(layer "F.SilkS")
		)
		(fp_line
			(start -0.7874 0.4064)
			(end -0.7874 -0.4064)
			(stroke
				(width 0.1524)
				(type default)
			)
			(layer "F.SilkS")
		)
		(fp_line
			(start -0.7874 -0.4064)
			(end 0.7874 -0.4064)
			(stroke
				(width 0.1524)
				(type default)
			)
			(layer "F.SilkS")
		)
		(fp_line
			(start 0.67945 0.3048)
			(end 0.120396 0.3048)
			(stroke
				(width 0.1)
				(type default)
			)
			(layer "F.Fab")
		)
		(fp_line
			(start 0.67945 -0.3048)
			(end 0.67945 0.3048)
			(stroke
				(width 0.1)
				(type default)
			)
			(layer "F.Fab")
		)
		(fp_line
			(start 0.12065 -0.2794)
			(end 0.12065 -0.3048)
			(stroke
				(width 0.1)
				(type default)
			)
			(layer "F.Fab")
		)
		(fp_line
			(start 0.12065 -0.3048)
			(end 0.67945 -0.3048)
			(stroke
				(width 0.1)
				(type default)
			)
			(layer "F.Fab")
		)
		(fp_line
			(start 0.120396 0.3048)
			(end 0.120396 0.2794)
			(stroke
				(width 0.1)
				(type default)
			)
			(layer "F.Fab")
		)
		(fp_line
			(start 0.120396 0.2794)
			(end -0.12065 0.2794)
			(stroke
				(width 0.1)
				(type default)
			)
			(layer "F.Fab")
		)
		(fp_line
			(start -0.12065 0.3048)
			(end -0.67945 0.3048)
			(stroke
				(width 0.1)
				(type default)
			)
			(layer "F.Fab")
		)
		(fp_line
			(start -0.12065 0.2794)
			(end -0.12065 0.3048)
			(stroke
				(width 0.1)
				(type default)
			)
			(layer "F.Fab")
		)
		(fp_line
			(start -0.12065 -0.2794)
			(end 0.12065 -0.2794)
			(stroke
				(width 0.1)
				(type default)
			)
			(layer "F.Fab")
		)
		(fp_line
			(start -0.12065 -0.305054)
			(end -0.12065 -0.2794)
			(stroke
				(width 0.1)
				(type default)
			)
			(layer "F.Fab")
		)
		(fp_line
			(start -0.67945 0.3048)
			(end -0.67945 -0.305054)
			(stroke
				(width 0.1)
				(type default)
			)
			(layer "F.Fab")
		)
		(fp_line
			(start -0.67945 -0.305054)
			(end -0.12065 -0.305054)
			(stroke
				(width 0.1)
				(type default)
			)
			(layer "F.Fab")
		)
		(pad "1" smd circle
			(at -0.40005 0 180)
			(size 0 0)
			(layers "F.Cu" "F.Mask" "F.Paste")
			(net "PU_SMB_SML3_3V3AUX_PCH_SCL")
		)
		(pad "2" smd circle
			(at 0.40005 0 180)
			(size 0 0)
			(layers "F.Cu" "F.Mask" "F.Paste")
			(net "P3V3_AUX")
		)
	)
)
